# S9S_MB_2U (Grand Teton) — schematic netlist excerpt (pin names and nets, part order shuffled) for the footprints in the layout excerpt that follows; sources: Cadence DE-HDL packaged netlist, KiCad conversion of 03242023_DA0F0TMBIJ0_F0T_Motherboard_J_brd_V01_OCP.brd

PJ51  Q_SHORT  EMPTY  pkg SM  page 292 : \1\ = VSENSE_PVCCFA_EHV_CPU1_DP ; \2\ = SH_PVCCFA_EHV_CPU1
R1421  Q_RES  2K 1% CHIP  pkg 0402LF  page 219 : A = RST_RSMRST_PLD_R_N ; B = GND
R3326  Q_RES  0 5% CHIP  pkg 0402LF  page 212 : A = GPU_FPGA_READY_N ; B = GPU_FPGA_READY_R_N

(kicad_pcb
	(version 20260206)
	(generator "pcbnew")
	(generator_version "10.0")
	(general
		(thickness 1.6)
		(legacy_teardrops no)
	)
	(paper "A4")
	(title_block
		(title "03242023_DA0F0TMBIJ0_F0T_Motherboard_J_brd_V01_OCP.brd")
		(comment 1 "Grand Teton / footprints 2057-2059 of 6105")
	)
	(layers
		(0 "F.Cu" signal "TOP")
		(4 "In1.Cu" signal "GND")
		(6 "In2.Cu" signal "IN1")
		(8 "In3.Cu" signal "GND1")
		(10 "In4.Cu" signal "IN2")
		(12 "In5.Cu" signal "GND2")
		(14 "In6.Cu" signal "IN3")
		(16 "In7.Cu" signal "GND3")
		(18 "In8.Cu" signal "VCC")
		(20 "In9.Cu" signal "VCC1")
		(22 "In10.Cu" signal "GND4")
		(24 "In11.Cu" signal "IN4")
		(26 "In12.Cu" signal "GND5")
		(28 "In13.Cu" signal "IN5")
		(30 "In14.Cu" signal "GND6")
		(32 "In15.Cu" signal "IN6")
		(34 "In16.Cu" signal "GND7")
		(2 "B.Cu" signal "BOTTOM")
		(9 "F.Adhes" user "F.Adhesive")
		(11 "B.Adhes" user "B.Adhesive")
		(13 "F.Paste" user "Package Geometry/Pastemask Top")
		(15 "B.Paste" user "Package Geometry/Pastemask Bottom")
		(5 "F.SilkS" user "Ref Des/Silkscreen Top")
		(7 "B.SilkS" user "Ref Des/Silkscreen Bottom")
		(1 "F.Mask" user "Board Geometry/Soldermask Top")
		(3 "B.Mask" user "Board Geometry/Soldermask Bottom")
		(17 "Dwgs.User" user "User.Drawings")
		(19 "Cmts.User" user "User.Comments")
		(21 "Eco1.User" user "User.Eco1")
		(23 "Eco2.User" user "User.Eco2")
		(25 "Edge.Cuts" user "Board Geometry/Outline")
		(27 "Margin" user)
		(31 "F.CrtYd" user "Package Geometry/Place Bound Top")
		(29 "B.CrtYd" user "Package Geometry/Place Bound Bottom")
		(35 "F.Fab" user "Ref Des/Assembly Top")
		(33 "B.Fab" user "Ref Des/Assembly Bottom")
	)
	(footprint ""
		(layer "F.Cu")
		(at 28.337002 -135.001 180)
		(property "Reference" "PJ51"
			(at 4.60756 -0.056896 0)
			(unlocked yes)
			(layer "F.SilkS")
			(effects
				(font
					(size 0.7874 0.5842)
					(thickness 0.1524)
				)
				(justify left)
			)
		)
		(property "Value" ""
			(at 0 0 180)
			(layer "F.Fab")
			(effects
				(font
					(size 1.27 1.27)
				)
			)
		)
		(duplicate_pad_numbers_are_jumpers no)
		(pad "1" smd circle
			(at -0.7493 0 270)
			(size 0 0)
			(layers "F.Cu" "F.Mask" "F.Paste")
			(net "VSENSE_PVCCFA_EHV_CPU1_DP")
		)
		(pad "2" smd rect
			(at 0.7493 0 90)
			(size 0.7112 0.8128)
			(layers "F.Cu" "F.Mask" "F.Paste")
			(net "SH_PVCCFA_EHV_CPU1")
		)
		(zone
			(layer "F.Cu")
			(hatch none 0.5)
			(connect_pads
				(clearance 0)
			)
			(min_thickness 0.25)
			(keepout
				(tracks allowed)
				(vias not_allowed)
				(pads allowed)
				(copperpour not_allowed)
				(footprints allowed)
			)
			(placement
				(enabled no)
				(sheetname "")
			)
			(fill
				(thermal_gap 0.5)
				(thermal_bridge_width 0.5)
				(island_removal_mode 0)
			)
			(polygon
				(pts
					(xy 27.130502 -134.5946) (xy 29.518102 -134.5946) (xy 29.518102 -135.412226) (xy 27.130502 -135.412226)
				)
			)
		)
	)
	(footprint ""
		(layer "F.Cu")
		(at 116.159534 -39.335456)
		(property "Reference" "R3326"
			(at 0 0 0)
			(layer "F.SilkS")
			(hide yes)
			(effects
				(font
					(size 1.27 1.27)
				)
			)
		)
		(property "Value" ""
			(at 0 0 0)
			(layer "F.Fab")
			(effects
				(font
					(size 1.27 1.27)
				)
			)
		)
		(duplicate_pad_numbers_are_jumpers no)
		(fp_line
			(start -0.7874 -0.4064)
			(end 0.7874 -0.4064)
			(stroke
				(width 0.1524)
				(type default)
			)
			(layer "F.SilkS")
		)
		(fp_line
			(start -0.7874 0.4064)
			(end -0.7874 -0.4064)
			(stroke
				(width 0.1524)
				(type default)
			)
			(layer "F.SilkS")
		)
		(fp_line
			(start 0.7874 -0.4064)
			(end 0.7874 0.4064)
			(stroke
				(width 0.1524)
				(type default)
			)
			(layer "F.SilkS")
		)
		(fp_line
			(start 0.7874 0.4064)
			(end -0.7874 0.4064)
			(stroke
				(width 0.1524)
				(type default)
			)
			(layer "F.SilkS")
		)
		(fp_line
			(start -0.67945 -0.305054)
			(end -0.12065 -0.305054)
			(stroke
				(width 0.1)
				(type default)
			)
			(layer "F.Fab")
		)
		(fp_line
			(start -0.67945 0.3048)
			(end -0.67945 -0.305054)
			(stroke
				(width 0.1)
				(type default)
			)
			(layer "F.Fab")
		)
		(fp_line
			(start -0.12065 -0.305054)
			(end -0.12065 -0.2794)
			(stroke
				(width 0.1)
				(type default)
			)
			(layer "F.Fab")
		)
		(fp_line
			(start -0.12065 -0.2794)
			(end 0.12065 -0.2794)
			(stroke
				(width 0.1)
				(type default)
			)
			(layer "F.Fab")
		)
		(fp_line
			(start -0.12065 0.2794)
			(end -0.12065 0.3048)
			(stroke
				(width 0.1)
				(type default)
			)
			(layer "F.Fab")
		)
		(fp_line
			(start -0.12065 0.3048)
			(end -0.67945 0.3048)
			(stroke
				(width 0.1)
				(type default)
			)
			(layer "F.Fab")
		)
		(fp_line
			(start 0.120396 0.2794)
			(end -0.12065 0.2794)
			(stroke
				(width 0.1)
				(type default)
			)
			(layer "F.Fab")
		)
		(fp_line
			(start 0.120396 0.3048)
			(end 0.120396 0.2794)
			(stroke
				(width 0.1)
				(type default)
			)
			(layer "F.Fab")
		)
		(fp_line
			(start 0.12065 -0.3048)
			(end 0.67945 -0.3048)
			(stroke
				(width 0.1)
				(type default)
			)
			(layer "F.Fab")
		)
		(fp_line
			(start 0.12065 -0.2794)
			(end 0.12065 -0.3048)
			(stroke
				(width 0.1)
				(type default)
			)
			(layer "F.Fab")
		)
		(fp_line
			(start 0.67945 -0.3048)
			(end 0.67945 0.3048)
			(stroke
				(width 0.1)
				(type default)
			)
			(layer "F.Fab")
		)
		(fp_line
			(start 0.67945 0.3048)
			(end 0.120396 0.3048)
			(stroke
				(width 0.1)
				(type default)
			)
			(layer "F.Fab")
		)
		(pad "1" smd circle
			(at -0.40005 0)
			(size 0 0)
			(layers "F.Cu" "F.Mask" "F.Paste")
			(net "GPU_FPGA_READY_N")
		)
		(pad "2" smd circle
			(at 0.40005 0)
			(size 0 0)
			(layers "F.Cu" "F.Mask" "F.Paste")
			(net "GPU_FPGA_READY_R_N")
		)
	)
	(footprint ""
		(layer "F.Cu")
		(at 197.19036 -119.344948)
		(property "Reference" "R1421"
			(at 0 0 0)
			(layer "F.SilkS")
			(hide yes)
			(effects
				(font
					(size 1.27 1.27)
				)
			)
		)
		(property "Value" ""
			(at 0 0 0)
			(layer "F.Fab")
			(effects
				(font
					(size 1.27 1.27)
				)
			)
		)
		(duplicate_pad_numbers_are_jumpers no)
		(fp_line
			(start -0.7874 -0.4064)
			(end 0.7874 -0.4064)
			(stroke
				(width 0.1524)
				(type default)
			)
			(layer "F.SilkS")
		)
		(fp_line
			(start -0.7874 0.4064)
			(end -0.7874 -0.4064)
			(stroke
				(width 0.1524)
				(type default)
			)
			(layer "F.SilkS")
		)
		(fp_line
			(start 0.7874 -0.4064)
			(end 0.7874 0.4064)
			(stroke
				(width 0.1524)
				(type default)
			)
			(layer "F.SilkS")
		)
		(fp_line
			(start 0.7874 0.4064)
			(end -0.7874 0.4064)
			(stroke
				(width 0.1524)
				(type default)
			)
			(layer "F.SilkS")
		)
		(fp_line
			(start -0.67945 -0.305054)
			(end -0.12065 -0.305054)
			(stroke
				(width 0.1)
				(type default)
			)
			(layer "F.Fab")
		)
		(fp_line
			(start -0.67945 0.3048)
			(end -0.67945 -0.305054)
			(stroke
				(width 0.1)
				(type default)
			)
			(layer "F.Fab")
		)
		(fp_line
			(start -0.12065 -0.305054)
			(end -0.12065 -0.2794)
			(stroke
				(width 0.1)
				(type default)
			)
			(layer "F.Fab")
		)
		(fp_line
			(start -0.12065 -0.2794)
			(end 0.12065 -0.2794)
			(stroke
				(width 0.1)
				(type default)
			)
			(layer "F.Fab")
		)
		(fp_line
			(start -0.12065 0.2794)
			(end -0.12065 0.3048)
			(stroke
				(width 0.1)
				(type default)
			)
			(layer "F.Fab")
		)
		(fp_line
			(start -0.12065 0.3048)
			(end -0.67945 0.3048)
			(stroke
				(width 0.1)
				(type default)
			)
			(layer "F.Fab")
		)
		(fp_line
			(start 0.120396 0.2794)
			(end -0.12065 0.2794)
			(stroke
				(width 0.1)
				(type default)
			)
			(layer "F.Fab")
		)
		(fp_line
			(start 0.120396 0.3048)
			(end 0.120396 0.2794)
			(stroke
				(width 0.1)
				(type default)
			)
			(layer "F.Fab")
		)
		(fp_line
			(start 0.12065 -0.3048)
			(end 0.67945 -0.3048)
			(stroke
				(width 0.1)
				(type default)
			)
			(layer "F.Fab")
		)
		(fp_line
			(start 0.12065 -0.2794)
			(end 0.12065 -0.3048)
			(stroke
				(width 0.1)
				(type default)
			)
			(layer "F.Fab")
		)
		(fp_line
			(start 0.67945 -0.3048)
			(end 0.67945 0.3048)
			(stroke
				(width 0.1)
				(type default)
			)
			(layer "F.Fab")
		)
		(fp_line
			(start 0.67945 0.3048)
			(end 0.120396 0.3048)
			(stroke
				(width 0.1)
				(type default)
			)
			(layer "F.Fab")
		)
		(pad "1" smd circle
			(at -0.40005 0)
			(size 0 0)
			(layers "F.Cu" "F.Mask" "F.Paste")
			(net "RST_RSMRST_PLD_R_N")
		)
		(pad "2" smd circle
			(at 0.40005 0)
			(size 0 0)
			(layers "F.Cu" "F.Mask" "F.Paste")
			(net "GND")
		)
	)
)
